(kicad_pcb
	(version 20241229)
	(generator "pcbnew")
	(generator_version "9.0")
	(general
		(thickness 1.711)
		(legacy_teardrops no)
	)
	(paper "A4")
	(title_block
		(title "Antmicro Baseboard for Jetson AGX Thor")
		(date "2026-02-18")
		(rev "1.1.0")
		(company "Antmicro Ltd")
		(comment 1 "www.antmicro.com")
		(comment 9 "footprint 110 of 1170 (J1), pads 645-699 of 699")
	)
	(layers
		(0 "F.Cu" signal)
		(4 "In1.Cu" signal)
		(6 "In2.Cu" signal)
		(8 "In3.Cu" signal)
		(10 "In4.Cu" jumper)
		(12 "In5.Cu" signal)
		(14 "In6.Cu" signal)
		(16 "In7.Cu" signal)
		(18 "In8.Cu" signal)
		(2 "B.Cu" signal)
		(9 "F.Adhes" user "F.Adhesive")
		(11 "B.Adhes" user "B.Adhesive")
		(13 "F.Paste" user)
		(15 "B.Paste" user)
		(5 "F.SilkS" user "F.Silkscreen")
		(7 "B.SilkS" user "B.Silkscreen")
		(1 "F.Mask" user)
		(3 "B.Mask" user)
		(17 "Dwgs.User" user "User.Drawings")
		(19 "Cmts.User" user "User.Comments")
		(21 "Eco1.User" user "User.Eco1")
		(23 "Eco2.User" user "User.Eco2")
		(25 "Edge.Cuts" user)
		(27 "Margin" user)
		(31 "F.CrtYd" user "F.Courtyard")
		(29 "B.CrtYd" user "B.Courtyard")
		(35 "F.Fab" user)
		(33 "B.Fab" user)
	)
	(footprint "antmicro-footprints:Conn_Hermaphroditic_Molex_203456-0003_mirrored"
		(locked yes)
		(layer "F.Cu")
		(at 116.530532 78.15)
		(descr "Mirrored version of: https://www.molex.com/content/dam/molex/molex-dot-com/products/automated/en-us/salesdrawingpdf/203/203456/2034560003_sd.pdf")
		(property "Reference" "J1"
			(at -32.25 -11.2 180)
			(layer "F.SilkS")
			(effects
				(font
					(size 0.7 0.7)
					(thickness 0.15)
				)
				(justify right top)
			)
		)
		(property "Value" "Hermaphroditic_Molex_203456-0003_CUSTOM_Jetson_AGX_Thor_H8mm"
			(at 0.1 12.9 0)
			(layer "F.Fab")
			(effects
				(font
					(size 0.7 0.7)
					(thickness 0.15)
				)
				(justify right top)
			)
		)
		(property "Datasheet" "https://www.molex.com/content/dam/molex/molex-dot-com/products/automated/en-us/salesdrawingpdf/203/203456/2034560003_sd.pdf?inline"
			(at 0.1 0.2 0)
			(layer "F.Fab")
			(hide yes)
			(effects
				(font
					(size 0.7 0.7)
					(thickness 0.15)
				)
				(justify right top)
			)
		)
		(property "Description" "Mirror Mezz Hermaphroditic Connector, 5.50mm Connector Height, BGA-Attach Mounting, 7 Pair, 11 Row, 699 Circuits, 0.76µm Gold Plating, without Pegs"
			(at 0.1 0.2 0)
			(layer "F.Fab")
			(hide yes)
			(effects
				(font
					(size 0.7 0.7)
					(thickness 0.15)
				)
				(justify right top)
			)
		)
		(property "MPN" "203456-0003"
			(at 0 0 0)
			(unlocked yes)
			(layer "F.Fab")
			(hide yes)
			(effects
				(font
					(size 1 1)
					(thickness 0.15)
				)
			)
		)
		(property "Manufacturer" "Molex"
			(at 0 0 0)
			(unlocked yes)
			(layer "F.Fab")
			(hide yes)
			(effects
				(font
					(size 1 1)
					(thickness 0.15)
				)
			)
		)
		(property "Author" "Antmicro"
			(at 0 0 0)
			(unlocked yes)
			(layer "F.Fab")
			(hide yes)
			(effects
				(font
					(size 1 1)
					(thickness 0.15)
				)
			)
		)
		(property "License" "Apache-2.0"
			(at 0 0 0)
			(unlocked yes)
			(layer "F.Fab")
			(hide yes)
			(effects
				(font
					(size 1 1)
					(thickness 0.15)
				)
			)
		)
		(sheetname "/SoM_IO/")
		(sheetfile "som_io.kicad_sch")
		(solder_mask_margin 0.05)
		(attr smd)
		(pad "L9" smd circle
			(at -23 -7.5 90)
			(size 0.5 0.5)
			(layers "F.Cu" "F.Mask" "F.Paste")
			(net 649 "unconnected-(J1H-I2S7_DOUT-PadL9)")
			(pinfunction "I2S7_DOUT")
			(pintype "output+no_connect")
		)
		(pad "L10" smd circle
			(at -22.1 -7.5 90)
			(size 0.5 0.5)
			(layers "F.Cu" "F.Mask" "F.Paste")
			(net 495 "/SoM_Power/~{FORCE_RECOVERY}")
			(pinfunction "FORCE_RECOVERY_N")
			(pintype "input")
		)
		(pad "L11" smd circle
			(at -21.2 -7.5 90)
			(size 0.5 0.5)
			(layers "F.Cu" "F.Mask" "F.Paste")
			(net 793 "/SoM_Power/~{SLEEP_REQ}")
			(pinfunction "SLEEP_REQ_N")
			(pintype "input")
		)
		(pad "L12" smd circle
			(at -20.3 -7.5 90)
			(size 0.5 0.5)
			(layers "F.Cu" "F.Mask" "F.Paste")
			(net 1 "GND")
			(pinfunction "GND")
			(pintype "passive")
		)
		(pad "L13" smd circle
			(at -19 -7.5 90)
			(size 0.5 0.5)
			(layers "F.Cu" "F.Mask" "F.Paste")
			(net 1 "GND")
			(pinfunction "GND")
			(pintype "passive")
		)
		(pad "L14" smd circle
			(at -18.1 -7.5 90)
			(size 0.5 0.5)
			(layers "F.Cu" "F.Mask" "F.Paste")
			(net 107 "/SoM_IO/I2S_{M.2}.CLK")
			(pinfunction "I2S1_CLK")
			(pintype "bidirectional")
		)
		(pad "L15" smd circle
			(at -17.2 -7.5 90)
			(size 0.5 0.5)
			(layers "F.Cu" "F.Mask" "F.Paste")
			(net 580 "/SoM_IO/USBC1_FLG_1V8")
			(pinfunction "GPIO14")
			(pintype "passive")
		)
		(pad "L16" smd circle
			(at -16.3 -7.5 90)
			(size 0.5 0.5)
			(layers "F.Cu" "F.Mask" "F.Paste")
			(net 1 "GND")
			(pinfunction "GND")
			(pintype "passive")
		)
		(pad "L17" smd circle
			(at -15 -7.5 90)
			(size 0.5 0.5)
			(layers "F.Cu" "F.Mask" "F.Paste")
			(net 1 "GND")
			(pinfunction "GND")
			(pintype "passive")
		)
		(pad "L18" smd circle
			(at -14.1 -7.5 90)
			(size 0.5 0.5)
			(layers "F.Cu" "F.Mask" "F.Paste")
			(net 775 "/M.2/PCIe_{C5x4}.~{RST}")
			(pinfunction "PEX_C5_RST_N")
			(pintype "output")
		)
		(pad "L19" smd circle
			(at -13.2 -7.5 90)
			(size 0.5 0.5)
			(layers "F.Cu" "F.Mask" "F.Paste")
			(net 751 "/M.2/PCIe_{C5x4}.~{CLKREQ}")
			(pinfunction "PEX_C5_CLKREQ_N")
			(pintype "bidirectional")
		)
		(pad "L20" smd circle
			(at -12.3 -7.5 90)
			(size 0.5 0.5)
			(layers "F.Cu" "F.Mask" "F.Paste")
			(net 1 "GND")
			(pinfunction "GND")
			(pintype "passive")
		)
		(pad "L21" smd circle
			(at -11 -7.5 90)
			(size 0.5 0.5)
			(layers "F.Cu" "F.Mask" "F.Paste")
			(net 1 "GND")
			(pinfunction "GND")
			(pintype "passive")
		)
		(pad "L22" smd circle
			(at -10.1 -7.5 90)
			(size 0.5 0.5)
			(layers "F.Cu" "F.Mask" "F.Paste")
			(net 213 "+5V_SOM")
			(pinfunction "SYS_VIN_MV")
			(pintype "power_in")
		)
		(pad "L23" smd circle
			(at -9.2 -7.5 90)
			(size 0.5 0.5)
			(layers "F.Cu" "F.Mask" "F.Paste")
			(net 213 "+5V_SOM")
			(pinfunction "SYS_VIN_MV")
			(pintype "passive")
		)
		(pad "L24" smd circle
			(at -8.3 -7.5 90)
			(size 0.5 0.5)
			(layers "F.Cu" "F.Mask" "F.Paste")
			(net 1 "GND")
			(pinfunction "GND")
			(pintype "passive")
		)
		(pad "L25" smd circle
			(at -7 -7.5 90)
			(size 0.5 0.5)
			(layers "F.Cu" "F.Mask" "F.Paste")
			(net 1 "GND")
			(pinfunction "GND")
			(pintype "passive")
		)
		(pad "L26" smd circle
			(at -6.1 -7.5 90)
			(size 0.5 0.5)
			(layers "F.Cu" "F.Mask" "F.Paste")
			(net 213 "+5V_SOM")
			(pinfunction "SYS_VIN_MV")
			(pintype "passive")
		)
		(pad "L27" smd circle
			(at -5.2 -7.5 90)
			(size 0.5 0.5)
			(layers "F.Cu" "F.Mask" "F.Paste")
			(net 213 "+5V_SOM")
			(pinfunction "SYS_VIN_MV")
			(pintype "passive")
		)
		(pad "L28" smd circle
			(at -4.3 -7.5 90)
			(size 0.5 0.5)
			(layers "F.Cu" "F.Mask" "F.Paste")
			(net 1 "GND")
			(pinfunction "GND")
			(pintype "passive")
		)
		(pad "L29" smd circle
			(at -3 -7.5 90)
			(size 0.5 0.5)
			(layers "F.Cu" "F.Mask" "F.Paste")
			(net 1 "GND")
			(pinfunction "GND")
			(pintype "passive")
		)
		(pad "L30" smd circle
			(at -2.1 -7.5 90)
			(size 0.5 0.5)
			(layers "F.Cu" "F.Mask" "F.Paste")
			(net 213 "+5V_SOM")
			(pinfunction "SYS_VIN_MV")
			(pintype "passive")
		)
		(pad "L31" smd circle
			(at -1.2 -7.5 90)
			(size 0.5 0.5)
			(layers "F.Cu" "F.Mask" "F.Paste")
			(net 213 "+5V_SOM")
			(pinfunction "SYS_VIN_MV")
			(pintype "passive")
		)
		(pad "L32" smd circle
			(at -0.3 -7.5 90)
			(size 0.5 0.5)
			(layers "F.Cu" "F.Mask" "F.Paste")
			(net 1 "GND")
			(pinfunction "GND")
			(pintype "passive")
		)
		(pad "L33" smd circle
			(at 1 -7.5 90)
			(size 0.5 0.5)
			(layers "F.Cu" "F.Mask" "F.Paste")
			(net 1 "GND")
			(pinfunction "GND")
			(pintype "passive")
		)
		(pad "L34" smd circle
			(at 1.9 -7.5 90)
			(size 0.5 0.5)
			(layers "F.Cu" "F.Mask" "F.Paste")
			(net 213 "+5V_SOM")
			(pinfunction "SYS_VIN_MV")
			(pintype "passive")
		)
		(pad "L35" smd circle
			(at 2.8 -7.5 90)
			(size 0.5 0.5)
			(layers "F.Cu" "F.Mask" "F.Paste")
			(net 213 "+5V_SOM")
			(pinfunction "SYS_VIN_MV")
			(pintype "passive")
		)
		(pad "L36" smd circle
			(at 3.7 -7.5 90)
			(size 0.5 0.5)
			(layers "F.Cu" "F.Mask" "F.Paste")
			(net 1 "GND")
			(pinfunction "GND")
			(pintype "passive")
		)
		(pad "L37" smd circle
			(at 5 -7.5 90)
			(size 0.5 0.5)
			(layers "F.Cu" "F.Mask" "F.Paste")
			(net 1 "GND")
			(pinfunction "GND")
			(pintype "passive")
		)
		(pad "L38" smd circle
			(at 5.9 -7.5 90)
			(size 0.5 0.5)
			(layers "F.Cu" "F.Mask" "F.Paste")
			(net 213 "+5V_SOM")
			(pinfunction "SYS_VIN_MV")
			(pintype "passive")
		)
		(pad "L39" smd circle
			(at 6.8 -7.5 90)
			(size 0.5 0.5)
			(layers "F.Cu" "F.Mask" "F.Paste")
			(net 213 "+5V_SOM")
			(pinfunction "SYS_VIN_MV")
			(pintype "passive")
		)
		(pad "L40" smd circle
			(at 7.7 -7.5 90)
			(size 0.5 0.5)
			(layers "F.Cu" "F.Mask" "F.Paste")
			(net 1 "GND")
			(pinfunction "GND")
			(pintype "passive")
		)
		(pad "L41" smd circle
			(at 8.6 -7.5 90)
			(size 0.5 0.5)
			(layers "F.Cu" "F.Mask" "F.Paste")
			(net 566 "Net-(J1A-VM_SLEEP_N)")
			(pinfunction "VM_SLEEP_N")
			(pintype "output")
		)
		(pad "L42" smd circle
			(at 9.5 -7.5 90)
			(size 0.5 0.5)
			(layers "F.Cu" "F.Mask" "F.Paste")
			(net 700 "Net-(J1A-MV_LSW_MON)")
			(pinfunction "MV_LSW_MON")
			(pintype "input")
		)
		(pad "L43" smd circle
			(at 10.4 -7.5 90)
			(size 0.5 0.5)
			(layers "F.Cu" "F.Mask" "F.Paste")
			(net 1 "GND")
			(pinfunction "GND")
			(pintype "passive")
		)
		(pad "L44" smd circle
			(at 11.3 -7.5 90)
			(size 0.5 0.5)
			(layers "F.Cu" "F.Mask" "F.Paste")
			(net 664 "unconnected-(J1D-VM_I2C_SCK-PadL44)")
			(pinfunction "VM_I2C_SCK")
			(pintype "bidirectional+no_connect")
		)
		(pad "L45" smd circle
			(at 12.2 -7.5 90)
			(size 0.5 0.5)
			(layers "F.Cu" "F.Mask" "F.Paste")
			(net 734 "unconnected-(J1D-VM_I2C_DAT-PadL45)")
			(pinfunction "VM_I2C_DAT")
			(pintype "bidirectional+no_connect")
		)
		(pad "L46" smd circle
			(at 13.1 -7.5 90)
			(size 0.5 0.5)
			(layers "F.Cu" "F.Mask" "F.Paste")
			(net 1 "GND")
			(pinfunction "GND")
			(pintype "passive")
		)
		(pad "L47" smd circle
			(at 14 -7.5 90)
			(size 0.5 0.5)
			(layers "F.Cu" "F.Mask" "F.Paste")
			(net 601 "Net-(J1A-VM_INT_N)")
			(pinfunction "VM_INT_N")
			(pintype "input")
		)
		(pad "L48" smd circle
			(at 14.9 -7.5 90)
			(size 0.5 0.5)
			(layers "F.Cu" "F.Mask" "F.Paste")
			(net 654 "unconnected-(J1H-I2S7_DIN-PadL48)")
			(pinfunction "I2S7_DIN")
			(pintype "input+no_connect")
		)
		(pad "L49" smd circle
			(at 15.8 -7.5 90)
			(size 0.5 0.5)
			(layers "F.Cu" "F.Mask" "F.Paste")
			(net 712 "unconnected-(J1H-I2S7_LRCK-PadL49)")
			(pinfunction "I2S7_LRCK")
			(pintype "input+no_connect")
		)
		(pad "L50" smd circle
			(at 16.7 -7.5 90)
			(size 0.5 0.5)
			(layers "F.Cu" "F.Mask" "F.Paste")
			(net 705 "unconnected-(J1H-I2S7_SCLK-PadL50)")
			(pinfunction "I2S7_SCLK")
			(pintype "passive+no_connect")
		)
		(pad "L51" smd circle
			(at 17.6 -7.5 90)
			(size 0.5 0.5)
			(layers "F.Cu" "F.Mask" "F.Paste")
			(net 126 "/SoM_IO/UART1.RTS")
			(pinfunction "UART1_RTS")
			(pintype "output")
		)
		(pad "L52" smd circle
			(at 18.5 -7.5 90)
			(size 0.5 0.5)
			(layers "F.Cu" "F.Mask" "F.Paste")
			(net 605 "/SoM_Power/~{MODULE_SHDN}")
			(pinfunction "MODULE_SHDN_N")
			(pintype "output")
		)
		(pad "L53" smd circle
			(at 19.4 -7.5 90)
			(size 0.5 0.5)
			(layers "F.Cu" "F.Mask" "F.Paste")
			(net 4 "+3V3_AON")
			(pinfunction "SYS_VIN_SV")
			(pintype "power_in")
		)
		(pad "L54" smd circle
			(at 20.3 -7.5 90)
			(size 0.5 0.5)
			(layers "F.Cu" "F.Mask" "F.Paste")
			(net 1287 "/SoM_Power/MODULE_POWER_ON")
			(pinfunction "MODULE_POWER_ON")
			(pintype "input")
		)
		(pad "L55" smd circle
			(at 21.2 -7.5 90)
			(size 0.5 0.5)
			(layers "F.Cu" "F.Mask" "F.Paste")
			(net 246 "/SoM_Power/~{VDDIN_PWR_BAD}")
			(pinfunction "VDDIN_PWR_BAD_N")
			(pintype "bidirectional")
		)
		(pad "L56" smd circle
			(at 22.1 -7.5 90)
			(size 0.5 0.5)
			(layers "F.Cu" "F.Mask" "F.Paste")
			(net 621 "Net-(J1A-THERM_ALERT_N)")
			(pinfunction "THERM_ALERT_N")
			(pintype "output")
		)
		(pad "L57" smd circle
			(at 23 -7.5 90)
			(size 0.5 0.5)
			(layers "F.Cu" "F.Mask" "F.Paste")
			(net 763 "unconnected-(J1D-MCLK05-PadL57)")
			(pinfunction "MCLK05")
			(pintype "bidirectional+no_connect")
		)
		(pad "L58" smd circle
			(at 23.9 -7.5 90)
			(size 0.5 0.5)
			(layers "F.Cu" "F.Mask" "F.Paste")
			(net 741 "Net-(J1A-PERIPHERAL_RESET_N)")
			(pinfunction "PERIPHERAL_RESET_N")
			(pintype "input")
		)
		(pad "L59" smd circle
			(at 24.8 -7.5 90)
			(size 0.5 0.5)
			(layers "F.Cu" "F.Mask" "F.Paste")
			(net 760 "Net-(J1A-MODULE_POWER_GOOD)")
			(pinfunction "MODULE_POWER_GOOD")
			(pintype "output")
		)
		(pad "L60" smd circle
			(at 25.7 -7.5 90)
			(size 0.5 0.5)
			(layers "F.Cu" "F.Mask" "F.Paste")
			(net 702 "/SoM_Power/~{SYS_RESET}")
			(pinfunction "SYS_RESET_N")
			(pintype "bidirectional")
		)
		(pad "L61" smd circle
			(at 26.6 -7.5 90)
			(size 0.5 0.5)
			(layers "F.Cu" "F.Mask" "F.Paste")
			(net 85 "/SoM_Power/~{SOM_POWER_BTN}")
			(pinfunction "POWER_BTN_N")
			(pintype "bidirectional")
		)
		(pad "L62" smd circle
			(at 27.5 -7.5 90)
			(size 0.5 0.5)
			(layers "F.Cu" "F.Mask" "F.Paste")
			(net 1293 "/DCDC/CARRIER_PWR_ON")
			(pinfunction "CARRIER_POWER_ON")
			(pintype "output")
		)
		(pad "L63" smd circle
			(at 28.4 -7.5 90)
			(size 0.5 0.5)
			(layers "F.Cu" "F.Mask" "F.Paste")
			(net 1 "GND")
			(pinfunction "PRSNT1")
			(pintype "passive")
		)
	)
)
